# S9S_MB_2U (Grand Teton) — schematic netlist excerpt (pin names and nets, part order shuffled) for the footprints in the layout excerpt that follows; sources: Cadence DE-HDL packaged netlist, KiCad conversion of 03242023_DA0F0TMBIJ0_F0T_Motherboard_J_brd_V01_OCP.brd

R1470  Q_RES  33.2 1% CHIP  pkg 0402LF  page 223 : A = RST_PLTRST_PLD_B_N ; B = RST_PLTRST_B_MUX_N
H126  HOLE  EMPTY  pkg TH  page 311 : \1\ = NC
C1989  Q_CAP_DIFFBUS  DIFF BUS_0.22UF 6.3V 20% X6S  pkg C0201  page 181 : \1\ = P3E_PCH_E1S_TX_DP<3> ; \2\ = P3E_PCH_E1S_TX_C_DP<3>

(kicad_pcb
	(version 20260206)
	(generator "pcbnew")
	(generator_version "10.0")
	(general
		(thickness 1.6)
		(legacy_teardrops no)
	)
	(paper "A4")
	(title_block
		(title "03242023_DA0F0TMBIJ0_F0T_Motherboard_J_brd_V01_OCP.brd")
		(comment 1 "Grand Teton / footprints 2875-2877 of 6105")
	)
	(layers
		(0 "F.Cu" signal "TOP")
		(4 "In1.Cu" signal "GND")
		(6 "In2.Cu" signal "IN1")
		(8 "In3.Cu" signal "GND1")
		(10 "In4.Cu" signal "IN2")
		(12 "In5.Cu" signal "GND2")
		(14 "In6.Cu" signal "IN3")
		(16 "In7.Cu" signal "GND3")
		(18 "In8.Cu" signal "VCC")
		(20 "In9.Cu" signal "VCC1")
		(22 "In10.Cu" signal "GND4")
		(24 "In11.Cu" signal "IN4")
		(26 "In12.Cu" signal "GND5")
		(28 "In13.Cu" signal "IN5")
		(30 "In14.Cu" signal "GND6")
		(32 "In15.Cu" signal "IN6")
		(34 "In16.Cu" signal "GND7")
		(2 "B.Cu" signal "BOTTOM")
		(9 "F.Adhes" user "F.Adhesive")
		(11 "B.Adhes" user "B.Adhesive")
		(13 "F.Paste" user "Package Geometry/Pastemask Top")
		(15 "B.Paste" user "Package Geometry/Pastemask Bottom")
		(5 "F.SilkS" user "Ref Des/Silkscreen Top")
		(7 "B.SilkS" user "Ref Des/Silkscreen Bottom")
		(1 "F.Mask" user "Board Geometry/Soldermask Top")
		(3 "B.Mask" user "Board Geometry/Soldermask Bottom")
		(17 "Dwgs.User" user "User.Drawings")
		(19 "Cmts.User" user "User.Comments")
		(21 "Eco1.User" user "User.Eco1")
		(23 "Eco2.User" user "User.Eco2")
		(25 "Edge.Cuts" user "Board Geometry/Outline")
		(27 "Margin" user)
		(31 "F.CrtYd" user "Package Geometry/Place Bound Top")
		(29 "B.CrtYd" user "Package Geometry/Place Bound Bottom")
		(35 "F.Fab" user "Ref Des/Assembly Top")
		(33 "B.Fab" user "Ref Des/Assembly Bottom")
	)
	(footprint ""
		(layer "F.Cu")
		(at 201.00036 -118.074948)
		(property "Reference" "R1470"
			(at 0 0 0)
			(layer "F.SilkS")
			(hide yes)
			(effects
				(font
					(size 1.27 1.27)
				)
			)
		)
		(property "Value" ""
			(at 0 0 0)
			(layer "F.Fab")
			(effects
				(font
					(size 1.27 1.27)
				)
			)
		)
		(duplicate_pad_numbers_are_jumpers no)
		(fp_line
			(start -0.7874 -0.4064)
			(end 0.7874 -0.4064)
			(stroke
				(width 0.1524)
				(type default)
			)
			(layer "F.SilkS")
		)
		(fp_line
			(start -0.7874 0.4064)
			(end -0.7874 -0.4064)
			(stroke
				(width 0.1524)
				(type default)
			)
			(layer "F.SilkS")
		)
		(fp_line
			(start 0.7874 -0.4064)
			(end 0.7874 0.4064)
			(stroke
				(width 0.1524)
				(type default)
			)
			(layer "F.SilkS")
		)
		(fp_line
			(start 0.7874 0.4064)
			(end -0.7874 0.4064)
			(stroke
				(width 0.1524)
				(type default)
			)
			(layer "F.SilkS")
		)
		(fp_line
			(start -0.67945 -0.305054)
			(end -0.12065 -0.305054)
			(stroke
				(width 0.1)
				(type default)
			)
			(layer "F.Fab")
		)
		(fp_line
			(start -0.67945 0.3048)
			(end -0.67945 -0.305054)
			(stroke
				(width 0.1)
				(type default)
			)
			(layer "F.Fab")
		)
		(fp_line
			(start -0.12065 -0.305054)
			(end -0.12065 -0.2794)
			(stroke
				(width 0.1)
				(type default)
			)
			(layer "F.Fab")
		)
		(fp_line
			(start -0.12065 -0.2794)
			(end 0.12065 -0.2794)
			(stroke
				(width 0.1)
				(type default)
			)
			(layer "F.Fab")
		)
		(fp_line
			(start -0.12065 0.2794)
			(end -0.12065 0.3048)
			(stroke
				(width 0.1)
				(type default)
			)
			(layer "F.Fab")
		)
		(fp_line
			(start -0.12065 0.3048)
			(end -0.67945 0.3048)
			(stroke
				(width 0.1)
				(type default)
			)
			(layer "F.Fab")
		)
		(fp_line
			(start 0.120396 0.2794)
			(end -0.12065 0.2794)
			(stroke
				(width 0.1)
				(type default)
			)
			(layer "F.Fab")
		)
		(fp_line
			(start 0.120396 0.3048)
			(end 0.120396 0.2794)
			(stroke
				(width 0.1)
				(type default)
			)
			(layer "F.Fab")
		)
		(fp_line
			(start 0.12065 -0.3048)
			(end 0.67945 -0.3048)
			(stroke
				(width 0.1)
				(type default)
			)
			(layer "F.Fab")
		)
		(fp_line
			(start 0.12065 -0.2794)
			(end 0.12065 -0.3048)
			(stroke
				(width 0.1)
				(type default)
			)
			(layer "F.Fab")
		)
		(fp_line
			(start 0.67945 -0.3048)
			(end 0.67945 0.3048)
			(stroke
				(width 0.1)
				(type default)
			)
			(layer "F.Fab")
		)
		(fp_line
			(start 0.67945 0.3048)
			(end 0.120396 0.3048)
			(stroke
				(width 0.1)
				(type default)
			)
			(layer "F.Fab")
		)
		(pad "1" smd circle
			(at -0.40005 0)
			(size 0 0)
			(layers "F.Cu" "F.Mask" "F.Paste")
			(net "RST_PLTRST_PLD_B_N")
		)
		(pad "2" smd circle
			(at 0.40005 0)
			(size 0 0)
			(layers "F.Cu" "F.Mask" "F.Paste")
			(net "RST_PLTRST_B_MUX_N")
		)
	)
	(footprint ""
		(layer "F.Cu")
		(at 239.152684 -58.32729 180)
		(property "Reference" "C1989"
			(at 0 0 180)
			(layer "F.SilkS")
			(hide yes)
			(effects
				(font
					(size 1.27 1.27)
				)
			)
		)
		(property "Value" ""
			(at 0 0 180)
			(layer "F.Fab")
			(effects
				(font
					(size 1.27 1.27)
				)
			)
		)
		(duplicate_pad_numbers_are_jumpers no)
		(fp_line
			(start 0.299974 0.150114)
			(end -0.299974 0.150114)
			(stroke
				(width 0.1)
				(type default)
			)
			(layer "F.Fab")
		)
		(fp_line
			(start 0.299974 -0.150114)
			(end 0.299974 0.150114)
			(stroke
				(width 0.1)
				(type default)
			)
			(layer "F.Fab")
		)
		(fp_line
			(start -0.299974 0.150114)
			(end -0.299974 -0.150114)
			(stroke
				(width 0.1)
				(type default)
			)
			(layer "F.Fab")
		)
		(fp_line
			(start -0.299974 -0.150114)
			(end 0.299974 -0.150114)
			(stroke
				(width 0.1)
				(type default)
			)
			(layer "F.Fab")
		)
		(pad "1" smd rect
			(at -0.2667 0 180)
			(size 0.3048 0.381)
			(layers "F.Cu" "F.Mask" "F.Paste")
			(net "P3E_PCH_E1S_TX_DP<3>")
		)
		(pad "2" smd rect
			(at 0.2667 0 180)
			(size 0.3048 0.381)
			(layers "F.Cu" "F.Mask" "F.Paste")
			(net "P3E_PCH_E1S_TX_C_DP<3>")
		)
		(zone
			(layer "In1.Cu")
			(hatch none 0.5)
			(connect_pads
				(clearance 0)
			)
			(min_thickness 0.25)
			(keepout
				(tracks not_allowed)
				(vias allowed)
				(pads allowed)
				(copperpour not_allowed)
				(footprints allowed)
			)
			(placement
				(enabled no)
				(sheetname "")
			)
			(fill
				(thermal_gap 0.5)
				(thermal_bridge_width 0.5)
				(island_removal_mode 0)
			)
			(polygon
				(pts
					(arc
						(start 239.012984 -58.567574)
						(mid 239.066866 -58.545256)
						(end 239.089184 -58.491374)
					)
					(arc
						(start 239.089184 -58.161174)
						(mid 239.066866 -58.107292)
						(end 239.012984 -58.084974)
					)
					(arc
						(start 238.758984 -58.084974)
						(mid 238.705102 -58.107292)
						(end 238.682784 -58.161174)
					)
					(arc
						(start 238.682784 -58.491374)
						(mid 238.705102 -58.545256)
						(end 238.758984 -58.567574)
					)
				)
			)
		)
		(zone
			(layer "In1.Cu")
			(hatch none 0.5)
			(connect_pads
				(clearance 0)
			)
			(min_thickness 0.25)
			(keepout
				(tracks not_allowed)
				(vias allowed)
				(pads allowed)
				(copperpour not_allowed)
				(footprints allowed)
			)
			(placement
				(enabled no)
				(sheetname "")
			)
			(fill
				(thermal_gap 0.5)
				(thermal_bridge_width 0.5)
				(island_removal_mode 0)
			)
			(polygon
				(pts
					(arc
						(start 239.546384 -58.567574)
						(mid 239.600266 -58.545256)
						(end 239.622584 -58.491374)
					)
					(arc
						(start 239.622584 -58.161174)
						(mid 239.600266 -58.107292)
						(end 239.546384 -58.084974)
					)
					(arc
						(start 239.292384 -58.084974)
						(mid 239.238502 -58.107292)
						(end 239.216184 -58.161174)
					)
					(arc
						(start 239.216184 -58.491374)
						(mid 239.238502 -58.545256)
						(end 239.292384 -58.567574)
					)
				)
			)
		)
	)
	(footprint ""
		(layer "F.Cu")
		(at 29.954728 -153.76652)
		(property "Reference" "H126"
			(at -10.20572 0.41783 0)
			(unlocked yes)
			(layer "F.SilkS")
			(effects
				(font
					(size 0.7874 0.5842)
					(thickness 0.1524)
				)
				(justify left)
			)
		)
		(property "Value" ""
			(at 0 0 0)
			(layer "F.Fab")
			(effects
				(font
					(size 1.27 1.27)
				)
			)
		)
		(duplicate_pad_numbers_are_jumpers no)
		(fp_circle
			(center 0 0)
			(end 5.8166 0)
			(stroke
				(width 0.1524)
				(type default)
			)
			(fill no)
			(layer "F.SilkS")
		)
		(fp_circle
			(center 0 0)
			(end 5.8166 0)
			(stroke
				(width 0.1524)
				(type default)
			)
			(fill no)
			(layer "B.SilkS")
		)
		(fp_circle
			(center 0 0)
			(end 5.8166 0)
			(stroke
				(width 0.1)
				(type default)
			)
			(fill no)
			(layer "B.Fab")
		)
		(fp_circle
			(center 0 0)
			(end 5.8166 0)
			(stroke
				(width 0.1)
				(type default)
			)
			(fill no)
			(layer "F.Fab")
		)
		(pad "" np_thru_hole circle
			(at 0 0)
			(size 10.0076 10.0076)
			(drill 10.0076)
			(layers "*.Cu" "*.Mask")
			(clearance 0.381)
			(thermal_gap 0.381)
		)
	)
)
